# BASEBOARD_FAB2 (Tioga Pass) — schematic netlist excerpt (pin names and nets, part order shuffled) for the footprints in the layout excerpt that follows; sources: Cadence DE-HDL packaged netlist, KiCad conversion of Wiwynn_Tioga_Pass_MB.brd

EU7G1  PXM1310B  IC  pkg QFN  page 215
  BPWM1  = NC
  DNC(0)  = NC
  APWM3  = NC
  APWM2  = VR_PVDDQ_ABC_PWM2
  APWM1  = VR_PVDDQ_ABC_PWM1
  SDA  = SMB_VR_STBY_LVC3_SDA
  SCL  = SMB_VR_STBY_LVC3_SCL
  RESET_N  = NC
  AVRRDY  = PWRGD_PVDDQ_ABC_R
  AVREN  = VR_PVDDQ_ABC_VREN
  VRHOT_N  = IRQ_PVDDQ_ABC_VRHOT_LVT3_R_N
  PINALRT_N  = NC
  MP0  = PU_VR_PVDDQ_ABC_FAULT1
  MP1  = TP_PVDDQ_ABC_MP1
  VCLK  = SVID_CLK_PVDDQ_ABC
  VDIO  = SVID_VDIO_PVDDQ_ABC
  VALRT_N  = SVID_ALERT_PVDDQ_ABC
  MP2  = TP_PVDDQ_ABC_MP2
  AVSEN  = VR_PVDDQ_ABC_AVSP
  AVREF  = VSENSE_PVDDQ_ABC_N
  AIREF1  = VR_PVDDQ_ABC_AIREF1
  AISEN1  = ISENSE_PVDDQ_ABC_PH1_IMON
  AIREF2  = VR_PVDDQ_ABC_AIREF2
  AISEN2  = ISENSE_PVDDQ_ABC_PH2_IMON
  AIREF3  = NC
  AISEN3  = NC
  GND  = GND
  DNC(1)  = NC
  BVSEN  = NC
  BVREF  = NC
  BIREF1  = NC
  BISEN1  = GND
  XADDR2  = VR_PVDDQ_ABC_XADDR2
  BTSEN  = NC
  ATSEN  = A_TSENSE_PVDDQ_ABC
  XADDR1  = VR_PVDDQ_ABC_XADDR1
  VINSEN  = VR_PVDDQ_ABC_VINSEN
  IINSEN  = VR_PVDDQ_ABC_AIINSEN
  VDD  = VR_PVDDQ_ABC_VDD
  VD12  = VR_PVDDQ_ABC_VD12
  THPAD  = GND

(kicad_pcb
	(version 20260206)
	(generator "pcbnew")
	(generator_version "10.0")
	(general
		(thickness 1.6)
		(legacy_teardrops no)
	)
	(paper "A4")
	(title_block
		(title "Wiwynn_Tioga_Pass_MB.brd")
		(comment 1 "Tioga Pass / footprint 467 of 4770 (EU7G1), pads 18-34 of 41")
	)
	(layers
		(0 "F.Cu" signal "TOP")
		(4 "In1.Cu" signal "L2GND")
		(6 "In2.Cu" signal "L3")
		(8 "In3.Cu" signal "L4GND")
		(10 "In4.Cu" signal "L5")
		(12 "In5.Cu" signal "L6GND")
		(14 "In6.Cu" signal "L7VCC")
		(16 "In7.Cu" signal "L8VCC")
		(18 "In8.Cu" signal "L9GND")
		(20 "In9.Cu" signal "L10")
		(22 "In10.Cu" signal "L11GND")
		(24 "In11.Cu" signal "L12")
		(26 "In12.Cu" signal "L13GND")
		(2 "B.Cu" signal "BOTTOM")
		(9 "F.Adhes" user "F.Adhesive")
		(11 "B.Adhes" user "B.Adhesive")
		(13 "F.Paste" user "Package Geometry/Pastemask Top")
		(15 "B.Paste" user "Package Geometry/Pastemask Bottom")
		(5 "F.SilkS" user "Ref Des/Silkscreen Top")
		(7 "B.SilkS" user "Ref Des/Silkscreen Bottom")
		(1 "F.Mask" user "Board Geometry/Soldermask Top")
		(3 "B.Mask" user "Board Geometry/Soldermask Bottom")
		(17 "Dwgs.User" user "User.Drawings")
		(19 "Cmts.User" user "User.Comments")
		(21 "Eco1.User" user "User.Eco1")
		(23 "Eco2.User" user "User.Eco2")
		(25 "Edge.Cuts" user "Board Geometry/Outline")
		(27 "Margin" user)
		(31 "F.CrtYd" user "Package Geometry/Place Bound Top")
		(29 "B.CrtYd" user "Package Geometry/Place Bound Bottom")
		(35 "F.Fab" user "Ref Des/Assembly Top")
		(33 "B.Fab" user "Ref Des/Assembly Bottom")
	)
	(footprint ""
		(layer "F.Cu")
		(at 344.678 -15.367 -90)
		(property "Reference" "EU7G1"
			(at 1.27 4.03733 90)
			(unlocked yes)
			(layer "F.SilkS")
			(effects
				(font
					(size 0.7874 0.5842)
					(thickness 0.1524)
				)
				(justify left)
			)
		)
		(property "Value" ""
			(at 0 0 270)
			(layer "F.Fab")
			(effects
				(font
					(size 1.27 1.27)
				)
			)
		)
		(duplicate_pad_numbers_are_jumpers no)
		(pad "18" smd custom
			(at 0.999998 2.4511 270)
			(size 0.0508 0.0508)
			(layers "F.Cu" "F.Mask" "F.Paste")
			(net "TP_PVDDQ_ABC_MP2")
			(options
				(clearance outline)
				(anchor circle)
			)
			(primitives
				(gr_poly
					(pts
						(arc
							(start -0.1016 -0.254)
							(mid 0 -0.3556)
							(end 0.1016 -0.254)
						)
						(xy 0.1016 0.3556) (xy -0.1016 0.3556)
					)
					(width 0)
					(fill yes)
				)
			)
		)
		(pad "19" smd custom
			(at 1.400048 2.4511 270)
			(size 0.0508 0.0508)
			(layers "F.Cu" "F.Mask" "F.Paste")
			(net "VR_PVDDQ_ABC_AVSP")
			(options
				(clearance outline)
				(anchor circle)
			)
			(primitives
				(gr_poly
					(pts
						(arc
							(start -0.1016 -0.254)
							(mid 0 -0.3556)
							(end 0.1016 -0.254)
						)
						(xy 0.1016 0.3556) (xy -0.1016 0.3556)
					)
					(width 0)
					(fill yes)
				)
			)
		)
		(pad "20" smd custom
			(at 1.800098 2.4511 270)
			(size 0.0508 0.0508)
			(layers "F.Cu" "F.Mask" "F.Paste")
			(net "VSENSE_PVDDQ_ABC_N")
			(options
				(clearance outline)
				(anchor circle)
			)
			(primitives
				(gr_poly
					(pts
						(arc
							(start -0.1016 -0.254)
							(mid 0 -0.3556)
							(end 0.1016 -0.254)
						)
						(xy 0.1016 0.3556) (xy -0.1016 0.3556)
					)
					(width 0)
					(fill yes)
				)
			)
		)
		(pad "21" smd custom
			(at 2.4511 1.800098 270)
			(size 0.0508 0.0508)
			(layers "F.Cu" "F.Mask" "F.Paste")
			(net "VR_PVDDQ_ABC_AIREF1")
			(options
				(clearance outline)
				(anchor circle)
			)
			(primitives
				(gr_poly
					(pts
						(arc
							(start -0.254 0.1016)
							(mid -0.3556 0)
							(end -0.254 -0.1016)
						)
						(xy 0.3556 -0.1016) (xy 0.3556 0.1016)
					)
					(width 0)
					(fill yes)
				)
			)
		)
		(pad "22" smd custom
			(at 2.4511 1.400048 270)
			(size 0.0508 0.0508)
			(layers "F.Cu" "F.Mask" "F.Paste")
			(net "ISENSE_PVDDQ_ABC_PH1_IMON")
			(options
				(clearance outline)
				(anchor circle)
			)
			(primitives
				(gr_poly
					(pts
						(arc
							(start -0.254 0.1016)
							(mid -0.3556 0)
							(end -0.254 -0.1016)
						)
						(xy 0.3556 -0.1016) (xy 0.3556 0.1016)
					)
					(width 0)
					(fill yes)
				)
			)
		)
		(pad "23" smd custom
			(at 2.4511 0.999998 270)
			(size 0.0508 0.0508)
			(layers "F.Cu" "F.Mask" "F.Paste")
			(net "VR_PVDDQ_ABC_AIREF2")
			(options
				(clearance outline)
				(anchor circle)
			)
			(primitives
				(gr_poly
					(pts
						(arc
							(start -0.254 0.1016)
							(mid -0.3556 0)
							(end -0.254 -0.1016)
						)
						(xy 0.3556 -0.1016) (xy 0.3556 0.1016)
					)
					(width 0)
					(fill yes)
				)
			)
		)
		(pad "24" smd custom
			(at 2.4511 0.599948 270)
			(size 0.0508 0.0508)
			(layers "F.Cu" "F.Mask" "F.Paste")
			(net "ISENSE_PVDDQ_ABC_PH2_IMON")
			(options
				(clearance outline)
				(anchor circle)
			)
			(primitives
				(gr_poly
					(pts
						(arc
							(start -0.254 0.1016)
							(mid -0.3556 0)
							(end -0.254 -0.1016)
						)
						(xy 0.3556 -0.1016) (xy 0.3556 0.1016)
					)
					(width 0)
					(fill yes)
				)
			)
		)
		(pad "25" smd custom
			(at 2.4511 0.199898 270)
			(size 0.0508 0.0508)
			(layers "F.Cu" "F.Mask" "F.Paste")
			(net "Net_241")
			(options
				(clearance outline)
				(anchor circle)
			)
			(primitives
				(gr_poly
					(pts
						(arc
							(start -0.254 0.1016)
							(mid -0.3556 0)
							(end -0.254 -0.1016)
						)
						(xy 0.3556 -0.1016) (xy 0.3556 0.1016)
					)
					(width 0)
					(fill yes)
				)
			)
		)
		(pad "26" smd custom
			(at 2.4511 -0.199898 270)
			(size 0.0508 0.0508)
			(layers "F.Cu" "F.Mask" "F.Paste")
			(net "Net_240")
			(options
				(clearance outline)
				(anchor circle)
			)
			(primitives
				(gr_poly
					(pts
						(arc
							(start -0.254 0.1016)
							(mid -0.3556 0)
							(end -0.254 -0.1016)
						)
						(xy 0.3556 -0.1016) (xy 0.3556 0.1016)
					)
					(width 0)
					(fill yes)
				)
			)
		)
		(pad "27" smd custom
			(at 2.4511 -0.599948 270)
			(size 0.0508 0.0508)
			(layers "F.Cu" "F.Mask" "F.Paste")
			(net "GND")
			(options
				(clearance outline)
				(anchor circle)
			)
			(primitives
				(gr_poly
					(pts
						(arc
							(start -0.254 0.1016)
							(mid -0.3556 0)
							(end -0.254 -0.1016)
						)
						(xy 0.3556 -0.1016) (xy 0.3556 0.1016)
					)
					(width 0)
					(fill yes)
				)
			)
		)
		(pad "28" smd custom
			(at 2.4511 -0.999998 270)
			(size 0.0508 0.0508)
			(layers "F.Cu" "F.Mask" "F.Paste")
			(net "Net_346")
			(options
				(clearance outline)
				(anchor circle)
			)
			(primitives
				(gr_poly
					(pts
						(arc
							(start -0.254 0.1016)
							(mid -0.3556 0)
							(end -0.254 -0.1016)
						)
						(xy 0.3556 -0.1016) (xy 0.3556 0.1016)
					)
					(width 0)
					(fill yes)
				)
			)
		)
		(pad "29" smd custom
			(at 2.4511 -1.400048 270)
			(size 0.0508 0.0508)
			(layers "F.Cu" "F.Mask" "F.Paste")
			(net "Net_225")
			(options
				(clearance outline)
				(anchor circle)
			)
			(primitives
				(gr_poly
					(pts
						(arc
							(start -0.254 0.1016)
							(mid -0.3556 0)
							(end -0.254 -0.1016)
						)
						(xy 0.3556 -0.1016) (xy 0.3556 0.1016)
					)
					(width 0)
					(fill yes)
				)
			)
		)
		(pad "30" smd custom
			(at 2.4511 -1.800098 270)
			(size 0.0508 0.0508)
			(layers "F.Cu" "F.Mask" "F.Paste")
			(net "Net_224")
			(options
				(clearance outline)
				(anchor circle)
			)
			(primitives
				(gr_poly
					(pts
						(arc
							(start -0.254 0.1016)
							(mid -0.3556 0)
							(end -0.254 -0.1016)
						)
						(xy 0.3556 -0.1016) (xy 0.3556 0.1016)
					)
					(width 0)
					(fill yes)
				)
			)
		)
		(pad "31" smd custom
			(at 1.800098 -2.4511 270)
			(size 0.0508 0.0508)
			(layers "F.Cu" "F.Mask" "F.Paste")
			(net "Net_222")
			(options
				(clearance outline)
				(anchor circle)
			)
			(primitives
				(gr_poly
					(pts
						(arc
							(start 0.1016 0.254)
							(mid 0 0.3556)
							(end -0.1016 0.254)
						)
						(xy -0.1016 -0.3556) (xy 0.1016 -0.3556)
					)
					(width 0)
					(fill yes)
				)
			)
		)
		(pad "32" smd custom
			(at 1.400048 -2.4511 270)
			(size 0.0508 0.0508)
			(layers "F.Cu" "F.Mask" "F.Paste")
			(net "GND")
			(options
				(clearance outline)
				(anchor circle)
			)
			(primitives
				(gr_poly
					(pts
						(arc
							(start 0.1016 0.254)
							(mid 0 0.3556)
							(end -0.1016 0.254)
						)
						(xy -0.1016 -0.3556) (xy 0.1016 -0.3556)
					)
					(width 0)
					(fill yes)
				)
			)
		)
		(pad "33" smd custom
			(at 0.999998 -2.4511 270)
			(size 0.0508 0.0508)
			(layers "F.Cu" "F.Mask" "F.Paste")
			(net "VR_PVDDQ_ABC_XADDR2")
			(options
				(clearance outline)
				(anchor circle)
			)
			(primitives
				(gr_poly
					(pts
						(arc
							(start 0.1016 0.254)
							(mid 0 0.3556)
							(end -0.1016 0.254)
						)
						(xy -0.1016 -0.3556) (xy 0.1016 -0.3556)
					)
					(width 0)
					(fill yes)
				)
			)
		)
		(pad "34" smd custom
			(at 0.599948 -2.4511 270)
			(size 0.0508 0.0508)
			(layers "F.Cu" "F.Mask" "F.Paste")
			(net "Net_223")
			(options
				(clearance outline)
				(anchor circle)
			)
			(primitives
				(gr_poly
					(pts
						(arc
							(start 0.1016 0.254)
							(mid 0 0.3556)
							(end -0.1016 0.254)
						)
						(xy -0.1016 -0.3556) (xy 0.1016 -0.3556)
					)
					(width 0)
					(fill yes)
				)
			)
		)
	)
)
